FILE_TYPE = MULTI_PHYS_TABLE;
PART 'OSC_C'
{=================================================================================================================================================================================================}
:VALUE         | PACK_TYPE | MATERIAL | PART_NUMBER     = EnvComp                  | PART_NUMBER  | JEDEC_TYPE  | CLASS | DESCRIPTION                                                 | HEIGHT     | COMPONENT_TYPE | LPID   | SPEED_URL | Status |RPL| AML | Bus_Unit | Days ;
{================================================================================================================================================================================================}
'156.25MHZ'    | '6P10'    | 'OSC'    | 'G63831-004'(!) = ''                       | 'G63831-004' |'SOSR2013C'  | 'IC'  | '(USE SYM 17) OSC,CX0,6,5032,156.25MHZ,50PPM,3.3V,HCSL,SM'  | '0.053 IN' | 'SMTOTHER'     | '2535' | 'http://speed.intel.com:8081/speed/module/pdm/item/pdm_item_detail_direct.asp?item_cde=G63831-004&item_rev=01&url_param=unused' | '' | '' | '' | '' | '' 
'156.25MHZ'    | '6P10'    | 'EMPTY'  | 'G63831-004'(!) = ''                       | 'G63831-004' |'SOSR2013C'  | 'IO'  | '(USE SYM 17) OSC,CX0,6,5032,156.25MHZ,50PPM,3.3V,HCSL,SM'  | '0.053 IN' | 'SMTOTHER'     | '2535' | 'http://speed.intel.com:8081/speed/module/pdm/item/pdm_item_detail_direct.asp?item_cde=G63831-004&item_rev=01&url_param=unused' | '' | '' | '' | '' | '' 
'24MHZ'        | 'SM4'     | 'OSC'    | 'D34520-021'(!) = ''                       | 'D34520-021' |'SMY1310B'   | 'IC'  | '(USE SYM 11) OSC,CX0,4,SMD,24.00MHZ,25PPM,3.3V,CMOS,SM'    | '0.043 IN' | 'SMTOTHER'     | '3386' | 'http://speed.intel.com:8081/speed/module/pdm/item/pdm_item_detail_direct.asp?item_cde=D34520-021&item_rev=01&url_param=unused' | '' | '' | '' | '' | '' 
'24MHZ'        | 'SM4'     | 'EMPTY'  | 'D34520-021'(!) = ''                       | 'D34520-021' |'SMY1310B'   | 'IO'  | '(USE SYM 11) OSC,CX0,4,SMD,24.00MHZ,25PPM,3.3V,CMOS,SM'    | '0.043 IN' | 'SMTOTHER'     | '3386' | 'http://speed.intel.com:8081/speed/module/pdm/item/pdm_item_detail_direct.asp?item_cde=D34520-021&item_rev=01&url_param=unused' | '' | '' | '' | '' | '' 
END_PART
END.
